(kicad_pcb
	(version 20241229)
	(generator "pcbnew")
	(generator_version "9.0")
	(general
		(thickness 1.62)
		(legacy_teardrops no)
	)
	(paper "A3")
	(title_block
		(title "COM Express 7 Baseboard")
		(date "2025-02-04")
		(rev "1.1.2")
		(company "Antmicro Ltd")
		(comment 1 "www.antmicro.com")
		(comment 9 "footprints 175-178 of 802")
	)
	(layers
		(0 "F.Cu" signal)
		(4 "In1.Cu" signal)
		(6 "In2.Cu" signal)
		(8 "In3.Cu" signal)
		(10 "In4.Cu" signal)
		(12 "In5.Cu" signal)
		(14 "In6.Cu" signal)
		(2 "B.Cu" signal)
		(9 "F.Adhes" user "F.Adhesive")
		(11 "B.Adhes" user "B.Adhesive")
		(13 "F.Paste" user)
		(15 "B.Paste" user)
		(5 "F.SilkS" user "F.Silkscreen")
		(7 "B.SilkS" user "B.Silkscreen")
		(1 "F.Mask" user)
		(3 "B.Mask" user)
		(17 "Dwgs.User" user "User.Drawings")
		(19 "Cmts.User" user "User.Comments")
		(21 "Eco1.User" user "User.Eco1")
		(23 "Eco2.User" user "User.Eco2")
		(25 "Edge.Cuts" user)
		(27 "Margin" user)
		(31 "F.CrtYd" user "F.Courtyard")
		(29 "B.CrtYd" user "B.Courtyard")
		(35 "F.Fab" user)
		(33 "B.Fab" user)
	)
	(footprint "antmicro-footprints:LED_0603_1608Metric_G"
		(layer "F.Cu")
		(at 146.49 168.44 180)
		(descr "LED SMD 0603 Green")
		(tags "LED SMD 0603 Green")
		(property "Reference" "D7"
			(at 1.19 -0.47 0)
			(layer "F.SilkS")
			(effects
				(font
					(size 0.7 0.7)
					(thickness 0.15)
				)
				(justify right bottom)
			)
		)
		(property "Value" "LED_G_0603_LTST-C190GKT"
			(at -0.001 1.599 0)
			(layer "F.Fab")
			(effects
				(font
					(size 0.7 0.7)
					(thickness 0.15)
				)
				(justify right bottom)
			)
		)
		(property "Datasheet" "https://media.digikey.com/pdf/Data%20Sheets/Lite-On%20PDFs/LTST-C190GKT.pdf"
			(at 0 0 180)
			(layer "F.Fab")
			(hide yes)
			(effects
				(font
					(size 1.27 1.27)
					(thickness 0.15)
				)
			)
		)
		(property "Author" "Antmicro"
			(at 292.98 336.88 0)
			(layer "F.Fab")
			(hide yes)
			(effects
				(font
					(size 1 1)
					(thickness 0.15)
				)
			)
		)
		(property "Color" "Green"
			(at 292.98 336.88 0)
			(layer "F.Fab")
			(hide yes)
			(effects
				(font
					(size 1 1)
					(thickness 0.15)
				)
			)
		)
		(property "License" "Apache-2.0"
			(at 292.98 336.88 0)
			(layer "F.Fab")
			(hide yes)
			(effects
				(font
					(size 1 1)
					(thickness 0.15)
				)
			)
		)
		(property "MPN" "LTST-C190GKT"
			(at 292.98 336.88 0)
			(layer "F.Fab")
			(hide yes)
			(effects
				(font
					(size 1 1)
					(thickness 0.15)
				)
			)
		)
		(property "Manufacturer" "Lite-On"
			(at 292.98 336.88 0)
			(layer "F.Fab")
			(hide yes)
			(effects
				(font
					(size 1 1)
					(thickness 0.15)
				)
			)
		)
		(property "Public" "False"
			(at 292.98 336.88 0)
			(layer "F.Fab")
			(hide yes)
			(effects
				(font
					(size 1 1)
					(thickness 0.15)
				)
			)
		)
		(sheetname "2xSFP+")
		(sheetfile "2xSFP+.kicad_sch")
		(attr smd)
		(fp_line
			(start 0.22 0.35)
			(end -0.22 0.35)
			(stroke
				(width 0.15)
				(type solid)
			)
			(layer "F.SilkS")
		)
		(fp_line
			(start 0.22 -0.35)
			(end -0.22 -0.35)
			(stroke
				(width 0.15)
				(type solid)
			)
			(layer "F.SilkS")
		)
		(fp_line
			(start 0.105328 0.201008)
			(end 0.105328 -0.198992)
			(stroke
				(width 0.1)
				(type solid)
			)
			(layer "F.SilkS")
		)
		(fp_line
			(start 0.105328 0.201008)
			(end -0.094672 0.001008)
			(stroke
				(width 0.1)
				(type solid)
			)
			(layer "F.SilkS")
		)
		(fp_line
			(start 0.105328 0.001008)
			(end 0.24 0.001)
			(stroke
				(width 0.1)
				(type solid)
			)
			(layer "F.SilkS")
		)
		(fp_line
			(start -0.094672 0.201008)
			(end -0.094672 -0.198992)
			(stroke
				(width 0.1)
				(type solid)
			)
			(layer "F.SilkS")
		)
		(fp_line
			(start -0.094672 0.001008)
			(end 0.105328 -0.198992)
			(stroke
				(width 0.1)
				(type solid)
			)
			(layer "F.SilkS")
		)
		(fp_line
			(start -0.094672 0.001008)
			(end -0.24 0.001008)
			(stroke
				(width 0.1)
				(type solid)
			)
			(layer "F.SilkS")
		)
		(fp_line
			(start -1.18 -0.319)
			(end -1.18 0.321)
			(stroke
				(width 0.15)
				(type solid)
			)
			(layer "F.SilkS")
		)
		(fp_rect
			(start 1.25 0.65)
			(end -1.25 -0.65)
			(stroke
				(width 0.05)
				(type solid)
			)
			(fill no)
			(layer "F.CrtYd")
		)
		(fp_line
			(start 0.599 0)
			(end 0.201 0)
			(stroke
				(width 0.15)
				(type solid)
			)
			(layer "F.Fab")
		)
		(fp_line
			(start 0.201 0.2)
			(end 0.201 0)
			(stroke
				(width 0.15)
				(type solid)
			)
			(layer "F.Fab")
		)
		(fp_line
			(start 0.201 0)
			(end 0.201 -0.202)
			(stroke
				(width 0.15)
				(type solid)
			)
			(layer "F.Fab")
		)
		(fp_line
			(start 0.201 -0.202)
			(end -0.101 0)
			(stroke
				(width 0.15)
				(type solid)
			)
			(layer "F.Fab")
		)
		(fp_line
			(start -0.101 0)
			(end 0.201 0.2)
			(stroke
				(width 0.15)
				(type solid)
			)
			(layer "F.Fab")
		)
		(fp_line
			(start -0.199 0.2)
			(end -0.199 0.1)
			(stroke
				(width 0.15)
				(type solid)
			)
			(layer "F.Fab")
		)
		(fp_line
			(start -0.199 0)
			(end -0.597 0)
			(stroke
				(width 0.15)
				(type solid)
			)
			(layer "F.Fab")
		)
		(fp_line
			(start -0.199 -0.202)
			(end -0.199 0.1)
			(stroke
				(width 0.15)
				(type solid)
			)
			(layer "F.Fab")
		)
		(fp_rect
			(start 0.848 0.4)
			(end -0.85 -0.402)
			(stroke
				(width 0.15)
				(type solid)
			)
			(fill no)
			(layer "F.Fab")
		)
		(pad "1" smd roundrect
			(at -0.7 0)
			(size 0.8 1)
			(layers "F.Cu" "F.Mask" "F.Paste")
			(roundrect_rratio 0.2)
			(net 932 "Net-(D7-C)")
			(pinfunction "C")
			(pintype "passive")
			(teardrops
				(best_length_ratio 0.2)
				(max_length 1)
				(best_width_ratio 0.9)
				(max_width 2)
				(curved_edges yes)
				(filter_ratio 0.9)
				(enabled yes)
				(allow_two_segments yes)
				(prefer_zone_connections yes)
			)
		)
		(pad "2" smd roundrect
			(at 0.7 0)
			(size 0.8 1)
			(layers "F.Cu" "F.Mask" "F.Paste")
			(roundrect_rratio 0.2)
			(net 2 "+3V3")
			(pinfunction "A")
			(pintype "passive")
			(teardrops
				(best_length_ratio 0.2)
				(max_length 1)
				(best_width_ratio 0.9)
				(max_width 2)
				(curved_edges yes)
				(filter_ratio 0.9)
				(enabled yes)
				(allow_two_segments yes)
				(prefer_zone_connections yes)
			)
		)
	)
	(footprint "antmicro-footprints:R_0402_1005Metric"
		(layer "F.Cu")
		(at 178.4 142.999998 180)
		(descr "Resistor SMD 0402")
		(tags "resistor SMD 0402")
		(property "Reference" "R37"
			(at -2.95 -0.45 0)
			(layer "F.SilkS")
			(effects
				(font
					(size 0.7 0.7)
					(thickness 0.15)
				)
				(justify right bottom)
			)
		)
		(property "Value" "R_0R_0402"
			(at -1.011843 1.772046 0)
			(layer "F.Fab")
			(effects
				(font
					(size 0.7 0.7)
					(thickness 0.15)
				)
				(justify right bottom)
			)
		)
		(property "Datasheet" "https://industrial.panasonic.com/cdbs/www-data/pdf/RDA0000/AOA0000C301.pdf"
			(at 0 0 0)
			(layer "F.Fab")
			(hide yes)
			(effects
				(font
					(size 1.27 1.27)
					(thickness 0.15)
				)
			)
		)
		(property "Author" "Antmicro"
			(at 337.9 328.52 0)
			(layer "F.Fab")
			(hide yes)
			(effects
				(font
					(size 1 1)
					(thickness 0.15)
				)
			)
		)
		(property "Current" "1A"
			(at 337.9 328.52 0)
			(layer "F.Fab")
			(hide yes)
			(effects
				(font
					(size 1 1)
					(thickness 0.15)
				)
			)
		)
		(property "License" "Apache-2.0"
			(at 337.9 328.52 0)
			(layer "F.Fab")
			(hide yes)
			(effects
				(font
					(size 1 1)
					(thickness 0.15)
				)
			)
		)
		(property "MPN" "ERJ2GE0R00X"
			(at 337.9 328.52 0)
			(layer "F.Fab")
			(hide yes)
			(effects
				(font
					(size 1 1)
					(thickness 0.15)
				)
			)
		)
		(property "Manufacturer" "Panasonic"
			(at 337.9 328.52 0)
			(layer "F.Fab")
			(hide yes)
			(effects
				(font
					(size 1 1)
					(thickness 0.15)
				)
			)
		)
		(property "Public" "False"
			(at 337.9 328.52 0)
			(layer "F.Fab")
			(hide yes)
			(effects
				(font
					(size 1 1)
					(thickness 0.15)
				)
			)
		)
		(property "Tolerance" ""
			(at 337.9 328.52 0)
			(layer "F.Fab")
			(hide yes)
			(effects
				(font
					(size 1 1)
					(thickness 0.15)
				)
			)
		)
		(property "Val" "0R"
			(at 337.9 328.52 0)
			(layer "F.Fab")
			(hide yes)
			(effects
				(font
					(size 1 1)
					(thickness 0.15)
				)
			)
		)
		(sheetname "2xSFP+")
		(sheetfile "2xSFP+.kicad_sch")
		(attr smd)
		(fp_rect
			(start -0.925 -0.47)
			(end 0.925 0.47)
			(stroke
				(width 0.05)
				(type default)
			)
			(fill no)
			(layer "F.CrtYd")
		)
		(fp_rect
			(start -0.5 -0.25)
			(end 0.5 0.25)
			(stroke
				(width 0.15)
				(type solid)
			)
			(fill no)
			(layer "F.Fab")
		)
		(pad "1" smd roundrect
			(at -0.48 0 180)
			(size 0.59 0.64)
			(layers "F.Cu" "F.Mask" "F.Paste")
			(roundrect_rratio 0.25)
			(net 425 "/2xSFP+/I2C_{SFP0}.SDA")
			(pintype "passive")
			(teardrops
				(best_length_ratio 0.2)
				(max_length 1)
				(best_width_ratio 0.9)
				(max_width 2)
				(curved_edges yes)
				(filter_ratio 0.9)
				(enabled yes)
				(allow_two_segments yes)
				(prefer_zone_connections yes)
			)
		)
		(pad "2" smd roundrect
			(at 0.48 0 180)
			(size 0.59 0.64)
			(layers "F.Cu" "F.Mask" "F.Paste")
			(roundrect_rratio 0.25)
			(net 164 "/2xSFP+/SDA0")
			(pintype "passive")
			(teardrops
				(best_length_ratio 0.2)
				(max_length 1)
				(best_width_ratio 0.9)
				(max_width 2)
				(curved_edges yes)
				(filter_ratio 0.9)
				(enabled yes)
				(allow_two_segments yes)
				(prefer_zone_connections yes)
			)
		)
	)
	(footprint "antmicro-footprints:TP_SMD_0.75mm"
		(layer "F.Cu")
		(at 145.95 129.56)
		(property "Reference" "TP75"
			(at 0.45 -1.25 90)
			(layer "F.SilkS")
			(effects
				(font
					(size 0.7 0.7)
					(thickness 0.15)
				)
				(justify left bottom)
			)
		)
		(property "Value" "TP_0.75mm_SMD"
			(at 0 1.2 0)
			(layer "F.Fab")
			(effects
				(font
					(size 0.7 0.7)
					(thickness 0.15)
				)
				(justify left bottom)
			)
		)
		(property "Author" "Antmicro"
			(at 0 0 0)
			(layer "F.Fab")
			(hide yes)
			(effects
				(font
					(size 1 1)
					(thickness 0.15)
				)
			)
		)
		(property "License" "Apache-2.0"
			(at 0 0 0)
			(layer "F.Fab")
			(hide yes)
			(effects
				(font
					(size 1 1)
					(thickness 0.15)
				)
			)
		)
		(property "MPN" ""
			(at 0 0 0)
			(layer "F.Fab")
			(hide yes)
			(effects
				(font
					(size 1 1)
					(thickness 0.15)
				)
			)
		)
		(property "Manufacturer" ""
			(at 0 0 0)
			(layer "F.Fab")
			(hide yes)
			(effects
				(font
					(size 1 1)
					(thickness 0.15)
				)
			)
		)
		(property "Public" "False"
			(at 0 0 0)
			(layer "F.Fab")
			(hide yes)
			(effects
				(font
					(size 1 1)
					(thickness 0.15)
				)
			)
		)
		(sheetname "KR to SFI #1")
		(sheetfile "kr_sfi.kicad_sch")
		(attr exclude_from_pos_files exclude_from_bom)
		(fp_circle
			(center 0 0)
			(end 0.475 0)
			(stroke
				(width 0.05)
				(type default)
			)
			(fill no)
			(layer "F.CrtYd")
		)
		(pad "1" smd circle
			(at 0 0)
			(size 0.75 0.75)
			(layers "F.Cu" "F.Mask")
			(net 738 "Net-(U43B-LS_OK_{IN_B})")
			(pinfunction "1")
			(pintype "passive")
			(teardrops
				(best_length_ratio 0.4)
				(max_length 1)
				(best_width_ratio 0.9)
				(max_width 2)
				(curved_edges yes)
				(filter_ratio 0.9)
				(enabled yes)
				(allow_two_segments yes)
				(prefer_zone_connections yes)
			)
		)
	)
	(footprint "antmicro-footprints:Mech_Lightpipe_Bivar_SLP3-300-250-F"
		(layer "F.Cu")
		(at 105.1405 76.266 -90)
		(property "Reference" "H5"
			(at -0.056 -1.5595 270)
			(unlocked yes)
			(layer "F.SilkS")
			(effects
				(font
					(size 0.7 0.7)
					(thickness 0.15)
				)
				(justify left bottom)
			)
		)
		(property "Value" "Lightpipe_Bivar_SLP3-300-250-F"
			(at 0 6.6 270)
			(unlocked yes)
			(layer "F.Fab")
			(effects
				(font
					(size 0.7 0.7)
					(thickness 0.15)
				)
				(justify left bottom)
			)
		)
		(property "Datasheet" "https://www.bivar.com/parts_content/Datasheets/SLP3-XXX-XXX-X.pdf"
			(at 0 0 90)
			(layer "F.Fab")
			(hide yes)
			(effects
				(font
					(size 1.27 1.27)
					(thickness 0.15)
				)
			)
		)
		(property "Manufacturer" "BIVAR"
			(at 0 0 270)
			(unlocked yes)
			(layer "F.Fab")
			(hide yes)
			(effects
				(font
					(size 1 1)
					(thickness 0.15)
				)
			)
		)
		(property "MPN" "SLP3-150-300-F"
			(at 0 0 270)
			(unlocked yes)
			(layer "F.Fab")
			(hide yes)
			(effects
				(font
					(size 1 1)
					(thickness 0.15)
				)
			)
		)
		(property "Author" "Antmicro"
			(at 0 0 270)
			(unlocked yes)
			(layer "F.Fab")
			(hide yes)
			(effects
				(font
					(size 1 1)
					(thickness 0.15)
				)
			)
		)
		(property "License" "Apache-2.0"
			(at 0 0 270)
			(unlocked yes)
			(layer "F.Fab")
			(hide yes)
			(effects
				(font
					(size 1 1)
					(thickness 0.15)
				)
			)
		)
		(sheetname "Misc")
		(sheetfile "misc.kicad_sch")
		(attr through_hole)
		(fp_rect
			(start -1.04 -1.225)
			(end 3.559 5.326)
			(stroke
				(width 0.15)
				(type solid)
			)
			(fill no)
			(layer "F.SilkS")
		)
		(fp_rect
			(start -1.3 4.196)
			(end 3.819 5.596)
			(stroke
				(width 0.05)
				(type solid)
			)
			(fill no)
			(layer "F.CrtYd")
		)
		(fp_rect
			(start -1.301 -1.504)
			(end 3.819 1.196)
			(stroke
				(width 0.05)
				(type solid)
			)
			(fill no)
			(layer "F.CrtYd")
		)
		(fp_line
			(start 0.55 2.5)
			(end 1.25 2.5)
			(stroke
				(width 0.15)
				(type solid)
			)
			(layer "F.Fab")
		)
		(fp_line
			(start 1.25 2.5)
			(end 1.25 3.201)
			(stroke
				(width 0.15)
				(type solid)
			)
			(layer "F.Fab")
		)
		(fp_line
			(start 1.25 2.5)
			(end 1.95 2.5)
			(stroke
				(width 0.15)
				(type solid)
			)
			(layer "F.Fab")
		)
		(fp_line
			(start 1.25 1.8)
			(end 1.25 2.5)
			(stroke
				(width 0.15)
				(type solid)
			)
			(layer "F.Fab")
		)
		(fp_rect
			(start -0.791 1.376)
			(end 3.309 3.625)
			(stroke
				(width 0.15)
				(type solid)
			)
			(fill no)
			(layer "F.Fab")
		)
		(pad "" np_thru_hole circle
			(at 0 0 270)
			(size 1.2 1.2)
			(drill 1.3208)
			(layers "F&B.Cu" "*.Mask")
		)
		(pad "" np_thru_hole circle
			(at 2.5 0 270)
			(size 1.2 1.2)
			(drill 1.3208)
			(layers "F&B.Cu" "*.Mask")
		)
	)
)
